# T6G (Grand Teton) — schematic netlist excerpt (pin names and nets, part order shuffled) for the footprints in the layout excerpt that follows; sources: Cadence DE-HDL packaged netlist, KiCad conversion of 04192023_DAF0TMB3IC0_F0TG_MB_C_brd_V02_OCP.brd

J212  CONN10_HBC1051L300D8H  CONN10_HBC1051-L300D-8H IO  pkg HEADER2X5XJ  page 27
  \1\  = CPU0_XTRIG_L4
  \2\  = CPU1_XTRIG_L4
  \3\  = CPU0_XTRIG_L5
  \4\  = CPU1_XTRIG_L5
  \5\  = CPU0_XTRIG_L6
  \6\  = CPU1_XTRIG_L6
  \7\  = CPU0_XTRIG_L7
  \8\  = CPU1_XTRIG_L7
  \9\  = NC
  \10\  = NC

R6299  Q_RES  0 5% CHIP  pkg 0402LF  page 178 : A = USB_HUB2_TI_OVERCUR3 ; B = USB_HUB2_TI_OVERCUR3_MRP_CFG_BC_EN

(kicad_pcb
	(version 20260206)
	(generator "pcbnew")
	(generator_version "10.0")
	(general
		(thickness 1.6)
		(legacy_teardrops no)
	)
	(paper "A4")
	(title_block
		(title "04192023_DAF0TMB3IC0_F0TG_MB_C_brd_V02_OCP.brd")
		(comment 1 "Grand Teton / footprints 863-864 of 8354")
	)
	(layers
		(0 "F.Cu" signal "TOP")
		(4 "In1.Cu" signal "GND")
		(6 "In2.Cu" signal "IN1")
		(8 "In3.Cu" signal "GND1")
		(10 "In4.Cu" signal "IN2")
		(12 "In5.Cu" signal "GND2")
		(14 "In6.Cu" signal "IN3")
		(16 "In7.Cu" signal "GND3")
		(18 "In8.Cu" signal "VCC")
		(20 "In9.Cu" signal "VCC1")
		(22 "In10.Cu" signal "GND4")
		(24 "In11.Cu" signal "IN4")
		(26 "In12.Cu" signal "GND5")
		(28 "In13.Cu" signal "IN5")
		(30 "In14.Cu" signal "GND6")
		(32 "In15.Cu" signal "IN6")
		(34 "In16.Cu" signal "GND7")
		(2 "B.Cu" signal "BOTTOM")
		(9 "F.Adhes" user "F.Adhesive")
		(11 "B.Adhes" user "B.Adhesive")
		(13 "F.Paste" user "Package Geometry/Pastemask Top")
		(15 "B.Paste" user "Package Geometry/Pastemask Bottom")
		(5 "F.SilkS" user "Ref Des/Silkscreen Top")
		(7 "B.SilkS" user "Ref Des/Silkscreen Bottom")
		(1 "F.Mask" user "Board Geometry/Soldermask Top")
		(3 "B.Mask" user "Board Geometry/Soldermask Bottom")
		(17 "Dwgs.User" user "User.Drawings")
		(19 "Cmts.User" user "User.Comments")
		(21 "Eco1.User" user "User.Eco1")
		(23 "Eco2.User" user "User.Eco2")
		(25 "Edge.Cuts" user "Board Geometry/Outline")
		(27 "Margin" user)
		(31 "F.CrtYd" user "Package Geometry/Place Bound Top")
		(29 "B.CrtYd" user "Package Geometry/Place Bound Bottom")
		(35 "F.Fab" user "Ref Des/Assembly Top")
		(33 "B.Fab" user "Ref Des/Assembly Bottom")
	)
	(footprint ""
		(layer "F.Cu")
		(at 112.597946 -52.86248 -90)
		(property "Reference" "R6299"
			(at 0 0 270)
			(layer "F.SilkS")
			(hide yes)
			(effects
				(font
					(size 1.27 1.27)
				)
			)
		)
		(property "Value" ""
			(at 0 0 270)
			(layer "F.Fab")
			(effects
				(font
					(size 1.27 1.27)
				)
			)
		)
		(duplicate_pad_numbers_are_jumpers no)
		(fp_line
			(start -0.7874 0.4064)
			(end -0.7874 -0.4064)
			(stroke
				(width 0.1524)
				(type default)
			)
			(layer "F.SilkS")
		)
		(fp_line
			(start 0.7874 0.4064)
			(end -0.7874 0.4064)
			(stroke
				(width 0.1524)
				(type default)
			)
			(layer "F.SilkS")
		)
		(fp_line
			(start -0.7874 -0.4064)
			(end 0.7874 -0.4064)
			(stroke
				(width 0.1524)
				(type default)
			)
			(layer "F.SilkS")
		)
		(fp_line
			(start 0.7874 -0.4064)
			(end 0.7874 0.4064)
			(stroke
				(width 0.1524)
				(type default)
			)
			(layer "F.SilkS")
		)
		(fp_line
			(start -0.67945 0.3048)
			(end -0.67945 -0.305054)
			(stroke
				(width 0.1)
				(type default)
			)
			(layer "F.Fab")
		)
		(fp_line
			(start -0.12065 0.3048)
			(end -0.67945 0.3048)
			(stroke
				(width 0.1)
				(type default)
			)
			(layer "F.Fab")
		)
		(fp_line
			(start 0.120396 0.3048)
			(end 0.120396 0.2794)
			(stroke
				(width 0.1)
				(type default)
			)
			(layer "F.Fab")
		)
		(fp_line
			(start 0.67945 0.3048)
			(end 0.120396 0.3048)
			(stroke
				(width 0.1)
				(type default)
			)
			(layer "F.Fab")
		)
		(fp_line
			(start -0.12065 0.2794)
			(end -0.12065 0.3048)
			(stroke
				(width 0.1)
				(type default)
			)
			(layer "F.Fab")
		)
		(fp_line
			(start 0.120396 0.2794)
			(end -0.12065 0.2794)
			(stroke
				(width 0.1)
				(type default)
			)
			(layer "F.Fab")
		)
		(fp_line
			(start -0.12065 -0.2794)
			(end 0.12065 -0.2794)
			(stroke
				(width 0.1)
				(type default)
			)
			(layer "F.Fab")
		)
		(fp_line
			(start 0.12065 -0.2794)
			(end 0.12065 -0.3048)
			(stroke
				(width 0.1)
				(type default)
			)
			(layer "F.Fab")
		)
		(fp_line
			(start 0.12065 -0.3048)
			(end 0.67945 -0.3048)
			(stroke
				(width 0.1)
				(type default)
			)
			(layer "F.Fab")
		)
		(fp_line
			(start 0.67945 -0.3048)
			(end 0.67945 0.3048)
			(stroke
				(width 0.1)
				(type default)
			)
			(layer "F.Fab")
		)
		(fp_line
			(start -0.67945 -0.305054)
			(end -0.12065 -0.305054)
			(stroke
				(width 0.1)
				(type default)
			)
			(layer "F.Fab")
		)
		(fp_line
			(start -0.12065 -0.305054)
			(end -0.12065 -0.2794)
			(stroke
				(width 0.1)
				(type default)
			)
			(layer "F.Fab")
		)
		(pad "1" smd circle
			(at -0.40005 0 270)
			(size 0 0)
			(layers "F.Cu" "F.Mask" "F.Paste")
			(net "USB_HUB2_TI_OVERCUR3")
		)
		(pad "2" smd circle
			(at 0.40005 0 270)
			(size 0 0)
			(layers "F.Cu" "F.Mask" "F.Paste")
			(net "USB_HUB2_TI_OVERCUR3_MRP_CFG_BC_EN")
		)
	)
	(footprint ""
		(layer "F.Cu")
		(at 353.38004 -44.250102 -90)
		(property "Reference" "J212"
			(at -3.273298 4.965192 0)
			(unlocked yes)
			(layer "F.SilkS")
			(effects
				(font
					(size 0.7874 0.5842)
					(thickness 0.1524)
				)
				(justify left)
			)
		)
		(property "Value" ""
			(at 0 0 270)
			(layer "F.Fab")
			(effects
				(font
					(size 1.27 1.27)
				)
			)
		)
		(duplicate_pad_numbers_are_jumpers no)
		(fp_line
			(start -1.219962 11.495024)
			(end 3.759962 11.495024)
			(stroke
				(width 0.1524)
				(type default)
			)
			(layer "F.SilkS")
		)
		(fp_line
			(start 3.759962 11.495024)
			(end 3.759962 -1.335024)
			(stroke
				(width 0.1524)
				(type default)
			)
			(layer "F.SilkS")
		)
		(fp_line
			(start -1.219962 -1.335024)
			(end -1.219962 11.495024)
			(stroke
				(width 0.1524)
				(type default)
			)
			(layer "F.SilkS")
		)
		(fp_line
			(start 3.759962 -1.335024)
			(end -1.219962 -1.335024)
			(stroke
				(width 0.1524)
				(type default)
			)
			(layer "F.SilkS")
		)
		(fp_poly
			(pts
				(xy -2.5146 -0.508) (xy -2.5146 0.508) (xy -1.4986 0)
			)
			(stroke
				(width 0)
				(type default)
			)
			(fill yes)
			(layer "F.SilkS")
		)
		(fp_line
			(start -1.219962 11.495024)
			(end 3.759962 11.495024)
			(stroke
				(width 0.1)
				(type default)
			)
			(layer "F.Fab")
		)
		(fp_line
			(start 3.759962 11.495024)
			(end 3.759962 -1.335024)
			(stroke
				(width 0.1)
				(type default)
			)
			(layer "F.Fab")
		)
		(fp_line
			(start -1.219962 -1.335024)
			(end -1.219962 11.495024)
			(stroke
				(width 0.1)
				(type default)
			)
			(layer "F.Fab")
		)
		(fp_line
			(start 3.759962 -1.335024)
			(end -1.219962 -1.335024)
			(stroke
				(width 0.1)
				(type default)
			)
			(layer "F.Fab")
		)
		(fp_poly
			(pts
				(xy -2.5146 -0.508) (xy -2.5146 0.508) (xy -1.4986 0)
			)
			(stroke
				(width 0)
				(type default)
			)
			(fill yes)
			(layer "F.Fab")
		)
		(pad "1" thru_hole rect
			(at 0 0 270)
			(size 1.6256 1.6256)
			(drill 1.1176)
			(layers "*.Cu" "*.Mask")
			(remove_unused_layers no)
			(net "CPU0_XTRIG_L4")
			(clearance 0)
			(padstack
				(mode front_inner_back)
				(layer "Inner"
					(shape circle)
					(size 1.6256 1.6256)
					(clearance 0)
				)
				(layer "B.Cu"
					(shape rect)
					(size 1.6256 1.6256)
					(clearance 0)
				)
			)
		)
		(pad "2" thru_hole circle
			(at 2.54 0 270)
			(size 1.6256 1.6256)
			(drill 1.1176)
			(layers "*.Cu" "*.Mask")
			(remove_unused_layers no)
			(net "CPU1_XTRIG_L4")
			(clearance 0)
		)
		(pad "3" thru_hole circle
			(at 0 2.54 270)
			(size 1.6256 1.6256)
			(drill 1.1176)
			(layers "*.Cu" "*.Mask")
			(remove_unused_layers no)
			(net "CPU0_XTRIG_L5")
			(clearance 0)
		)
		(pad "4" thru_hole circle
			(at 2.54 2.54 270)
			(size 1.6256 1.6256)
			(drill 1.1176)
			(layers "*.Cu" "*.Mask")
			(remove_unused_layers no)
			(net "CPU1_XTRIG_L5")
			(clearance 0)
		)
		(pad "5" thru_hole circle
			(at 0 5.08 270)
			(size 1.6256 1.6256)
			(drill 1.1176)
			(layers "*.Cu" "*.Mask")
			(remove_unused_layers no)
			(net "CPU0_XTRIG_L6")
			(clearance 0)
		)
		(pad "6" thru_hole circle
			(at 2.54 5.08 270)
			(size 1.6256 1.6256)
			(drill 1.1176)
			(layers "*.Cu" "*.Mask")
			(remove_unused_layers no)
			(net "CPU1_XTRIG_L6")
			(clearance 0)
		)
		(pad "7" thru_hole circle
			(at 0 7.62 270)
			(size 1.6256 1.6256)
			(drill 1.1176)
			(layers "*.Cu" "*.Mask")
			(remove_unused_layers no)
			(net "CPU0_XTRIG_L7")
			(clearance 0)
		)
		(pad "8" thru_hole circle
			(at 2.54 7.62 270)
			(size 1.6256 1.6256)
			(drill 1.1176)
			(layers "*.Cu" "*.Mask")
			(remove_unused_layers no)
			(net "CPU1_XTRIG_L7")
			(clearance 0)
		)
		(pad "9" thru_hole circle
			(at 0 10.16 270)
			(size 1.6256 1.6256)
			(drill 1.1176)
			(layers "*.Cu" "*.Mask")
			(remove_unused_layers no)
			(net "Net_1766")
			(clearance 0)
		)
		(pad "10" thru_hole circle
			(at 2.54 10.16 270)
			(size 1.6256 1.6256)
			(drill 1.1176)
			(layers "*.Cu" "*.Mask")
			(remove_unused_layers no)
			(net "Net_1765")
			(clearance 0)
		)
	)
)
